# T6G (Grand Teton) — schematic netlist excerpt (pin names and nets, part order shuffled) for the footprints in the layout excerpt that follows; sources: Cadence DE-HDL packaged netlist, KiCad conversion of 04192023_DAF0TMB3IC0_F0TG_MB_C_brd_V02_OCP.brd

C2340  Q_CAP  22UF 4V 20% X6S  pkg C0402  page 73 : A = PVDDCR_CPU0_P1 ; B = GND

U5  PCA9617ADP  EMPTY  pkg TSSOP8_3XB  page 160
  VCCA  = P3V3_AUX
  SCLA  = SMB_CPU0_CPU1_APML_BUF1_SCL
  SDAA  = SMB_CPU0_CPU1_APML_BUF1_SDA
  GND  = GND
  EN  = PU_U5_EN
  SDAB  = SMB_CPU0_CPU1_APML_BUF1_SDA_R1
  SCLB  = SMB_CPU0_CPU1_APML_BUF1_SCL_R1
  VCCB  = P3V3

(kicad_pcb
	(version 20260206)
	(generator "pcbnew")
	(generator_version "10.0")
	(general
		(thickness 1.6)
		(legacy_teardrops no)
	)
	(paper "A4")
	(title_block
		(title "04192023_DAF0TMB3IC0_F0TG_MB_C_brd_V02_OCP.brd")
		(comment 1 "Grand Teton / footprints 6510-6511 of 8354")
	)
	(layers
		(0 "F.Cu" signal "TOP")
		(4 "In1.Cu" signal "GND")
		(6 "In2.Cu" signal "IN1")
		(8 "In3.Cu" signal "GND1")
		(10 "In4.Cu" signal "IN2")
		(12 "In5.Cu" signal "GND2")
		(14 "In6.Cu" signal "IN3")
		(16 "In7.Cu" signal "GND3")
		(18 "In8.Cu" signal "VCC")
		(20 "In9.Cu" signal "VCC1")
		(22 "In10.Cu" signal "GND4")
		(24 "In11.Cu" signal "IN4")
		(26 "In12.Cu" signal "GND5")
		(28 "In13.Cu" signal "IN5")
		(30 "In14.Cu" signal "GND6")
		(32 "In15.Cu" signal "IN6")
		(34 "In16.Cu" signal "GND7")
		(2 "B.Cu" signal "BOTTOM")
		(9 "F.Adhes" user "F.Adhesive")
		(11 "B.Adhes" user "B.Adhesive")
		(13 "F.Paste" user "Package Geometry/Pastemask Top")
		(15 "B.Paste" user "Package Geometry/Pastemask Bottom")
		(5 "F.SilkS" user "Ref Des/Silkscreen Top")
		(7 "B.SilkS" user "Ref Des/Silkscreen Bottom")
		(1 "F.Mask" user "Board Geometry/Soldermask Top")
		(3 "B.Mask" user "Board Geometry/Soldermask Bottom")
		(17 "Dwgs.User" user "User.Drawings")
		(19 "Cmts.User" user "User.Comments")
		(21 "Eco1.User" user "User.Eco1")
		(23 "Eco2.User" user "User.Eco2")
		(25 "Edge.Cuts" user "Board Geometry/Outline")
		(27 "Margin" user)
		(31 "F.CrtYd" user "Package Geometry/Place Bound Top")
		(29 "B.CrtYd" user "Package Geometry/Place Bound Bottom")
		(35 "F.Fab" user "Ref Des/Assembly Top")
		(33 "B.Fab" user "Ref Des/Assembly Bottom")
	)
	(footprint ""
		(layer "B.Cu")
		(at 110.149386 -246.447564 -120)
		(property "Reference" "C2340"
			(at 0 0 60)
			(layer "B.SilkS")
			(hide yes)
			(effects
				(font
					(size 1.27 1.27)
				)
				(justify mirror)
			)
		)
		(property "Value" ""
			(at 0 0 60)
			(layer "B.Fab")
			(effects
				(font
					(size 1.27 1.27)
				)
				(justify mirror)
			)
		)
		(duplicate_pad_numbers_are_jumpers no)
		(fp_line
			(start 0.787516 0.406438)
			(end 0.787425 -0.40652)
			(stroke
				(width 0.1524)
				(type default)
			)
			(layer "B.SilkS")
		)
		(fp_line
			(start 0.787425 -0.40652)
			(end -0.787516 -0.406438)
			(stroke
				(width 0.1524)
				(type default)
			)
			(layer "B.SilkS")
		)
		(fp_line
			(start -0.787425 0.40652)
			(end 0.787516 0.406438)
			(stroke
				(width 0.1524)
				(type default)
			)
			(layer "B.SilkS")
		)
		(fp_line
			(start -0.787516 -0.406438)
			(end -0.787425 0.40652)
			(stroke
				(width 0.1524)
				(type default)
			)
			(layer "B.SilkS")
		)
		(fp_line
			(start 0.679568 0.304811)
			(end 0.679373 -0.305128)
			(stroke
				(width 0.1)
				(type default)
			)
			(layer "B.Fab")
		)
		(fp_line
			(start 0.120605 0.304905)
			(end 0.679568 0.304811)
			(stroke
				(width 0.1)
				(type default)
			)
			(layer "B.Fab")
		)
		(fp_line
			(start 0.120554 0.279418)
			(end 0.120605 0.304905)
			(stroke
				(width 0.1)
				(type default)
			)
			(layer "B.Fab")
		)
		(fp_line
			(start -0.120316 0.304686)
			(end -0.12024 0.279419)
			(stroke
				(width 0.1)
				(type default)
			)
			(layer "B.Fab")
		)
		(fp_line
			(start -0.12024 0.279419)
			(end 0.120554 0.279418)
			(stroke
				(width 0.1)
				(type default)
			)
			(layer "B.Fab")
		)
		(fp_line
			(start 0.679373 -0.305128)
			(end 0.120629 -0.30516)
			(stroke
				(width 0.1)
				(type default)
			)
			(layer "B.Fab")
		)
		(fp_line
			(start -0.6795 0.304908)
			(end -0.120316 0.304686)
			(stroke
				(width 0.1)
				(type default)
			)
			(layer "B.Fab")
		)
		(fp_line
			(start 0.120587 -0.279326)
			(end -0.120554 -0.279418)
			(stroke
				(width 0.1)
				(type default)
			)
			(layer "B.Fab")
		)
		(fp_line
			(start 0.120629 -0.30516)
			(end 0.120587 -0.279326)
			(stroke
				(width 0.1)
				(type default)
			)
			(layer "B.Fab")
		)
		(fp_line
			(start -0.120554 -0.279418)
			(end -0.120605 -0.304905)
			(stroke
				(width 0.1)
				(type default)
			)
			(layer "B.Fab")
		)
		(fp_line
			(start -0.120605 -0.304905)
			(end -0.679568 -0.304811)
			(stroke
				(width 0.1)
				(type default)
			)
			(layer "B.Fab")
		)
		(fp_line
			(start -0.679568 -0.304811)
			(end -0.6795 0.304908)
			(stroke
				(width 0.1)
				(type default)
			)
			(layer "B.Fab")
		)
		(pad "1" smd circle
			(at 0.40005 0 60)
			(size 0 0)
			(layers "B.Cu" "B.Mask" "B.Paste")
			(net "PVDDCR_CPU0_P1")
		)
		(pad "2" smd circle
			(at -0.40005 0 60)
			(size 0 0)
			(layers "B.Cu" "B.Mask" "B.Paste")
			(net "GND")
		)
	)
	(footprint ""
		(layer "B.Cu")
		(at 238.740442 -223.10217 90)
		(property "Reference" "U5"
			(at -1.79324 -2.775458 270)
			(unlocked yes)
			(layer "B.SilkS")
			(effects
				(font
					(size 0.7874 0.5842)
					(thickness 0.1524)
				)
				(justify left mirror)
			)
		)
		(property "Value" ""
			(at 0 0 90)
			(layer "B.Fab")
			(effects
				(font
					(size 1.27 1.27)
				)
				(justify mirror)
			)
		)
		(duplicate_pad_numbers_are_jumpers no)
		(fp_line
			(start 1.463548 -1.549908)
			(end 0.787908 -1.549908)
			(stroke
				(width 0.1524)
				(type default)
			)
			(layer "B.SilkS")
		)
		(fp_line
			(start 0.787908 -1.549908)
			(end 0 -0.762)
			(stroke
				(width 0.1524)
				(type default)
			)
			(layer "B.SilkS")
		)
		(fp_line
			(start -0.762 -1.549908)
			(end -1.463548 -1.549908)
			(stroke
				(width 0.1524)
				(type default)
			)
			(layer "B.SilkS")
		)
		(fp_line
			(start -1.463548 -1.549908)
			(end -1.463548 1.549908)
			(stroke
				(width 0.1524)
				(type default)
			)
			(layer "B.SilkS")
		)
		(fp_line
			(start 0 -0.762)
			(end -0.762 -1.549908)
			(stroke
				(width 0.1524)
				(type default)
			)
			(layer "B.SilkS")
		)
		(fp_line
			(start 1.463548 1.549908)
			(end 1.463548 -1.549908)
			(stroke
				(width 0.1524)
				(type default)
			)
			(layer "B.SilkS")
		)
		(fp_line
			(start -1.463548 1.549908)
			(end 1.463548 1.549908)
			(stroke
				(width 0.1524)
				(type default)
			)
			(layer "B.SilkS")
		)
		(fp_poly
			(pts
				(xy 3.314446 -0.304292) (xy 3.581908 -0.863346) (xy 2.888996 -0.851154)
			)
			(stroke
				(width 0)
				(type default)
			)
			(fill yes)
			(layer "B.SilkS")
		)
		(fp_line
			(start 1.549908 -1.549908)
			(end -1.549908 -1.549908)
			(stroke
				(width 0.1)
				(type default)
			)
			(layer "B.Fab")
		)
		(fp_line
			(start -1.549908 -1.549908)
			(end -1.549908 1.549908)
			(stroke
				(width 0.1)
				(type default)
			)
			(layer "B.Fab")
		)
		(fp_line
			(start 1.549908 1.549908)
			(end 1.549908 -1.549908)
			(stroke
				(width 0.1)
				(type default)
			)
			(layer "B.Fab")
		)
		(fp_line
			(start -1.549908 1.549908)
			(end 1.549908 1.549908)
			(stroke
				(width 0.1)
				(type default)
			)
			(layer "B.Fab")
		)
		(fp_poly
			(pts
				(xy 3.4798 -1.359916) (xy 2.86004 -1.050036) (xy 3.4798 -0.740156)
			)
			(stroke
				(width 0)
				(type default)
			)
			(fill yes)
			(layer "B.Fab")
		)
		(pad "1" smd rect
			(at 2.175002 -1.050036 180)
			(size 0.6096 1.1684)
			(layers "B.Cu" "B.Mask" "B.Paste")
			(net "P3V3_AUX")
		)
		(pad "2" smd rect
			(at 2.175002 -0.32512 180)
			(size 0.4318 1.1684)
			(layers "B.Cu" "B.Mask" "B.Paste")
			(net "SMB_CPU0_CPU1_APML_BUF1_SCL")
		)
		(pad "3" smd rect
			(at 2.175002 0.32512 180)
			(size 0.4318 1.1684)
			(layers "B.Cu" "B.Mask" "B.Paste")
			(net "SMB_CPU0_CPU1_APML_BUF1_SDA")
		)
		(pad "4" smd rect
			(at 2.175002 1.050036 180)
			(size 0.6096 1.1684)
			(layers "B.Cu" "B.Mask" "B.Paste")
			(net "GND")
		)
		(pad "5" smd rect
			(at -2.175002 1.050036 180)
			(size 0.6096 1.1684)
			(layers "B.Cu" "B.Mask" "B.Paste")
			(net "PU_U5_EN")
		)
		(pad "6" smd rect
			(at -2.175002 0.32512 180)
			(size 0.4318 1.1684)
			(layers "B.Cu" "B.Mask" "B.Paste")
			(net "SMB_CPU0_CPU1_APML_BUF1_SDA_R1")
		)
		(pad "7" smd rect
			(at -2.175002 -0.32512 180)
			(size 0.4318 1.1684)
			(layers "B.Cu" "B.Mask" "B.Paste")
			(net "SMB_CPU0_CPU1_APML_BUF1_SCL_R1")
		)
		(pad "8" smd rect
			(at -2.175002 -1.050036 180)
			(size 0.6096 1.1684)
			(layers "B.Cu" "B.Mask" "B.Paste")
			(net "P3V3")
		)
	)
)
